(kicad_pcb
	(version 20260206)
	(generator "pcbnew")
	(generator_version "10.0")
	(general
		(thickness 1.6)
		(legacy_teardrops no)
	)
	(paper "A4")
	(title_block
		(title "03242023_DA0F0TMBIJ0_F0T_Motherboard_J_brd_V01_OCP.brd")
		(comment 1 "Grand Teton / footprints 5407-5412 of 6105")
	)
	(layers
		(0 "F.Cu" signal "TOP")
		(4 "In1.Cu" signal "GND")
		(6 "In2.Cu" signal "IN1")
		(8 "In3.Cu" signal "GND1")
		(10 "In4.Cu" signal "IN2")
		(12 "In5.Cu" signal "GND2")
		(14 "In6.Cu" signal "IN3")
		(16 "In7.Cu" signal "GND3")
		(18 "In8.Cu" signal "VCC")
		(20 "In9.Cu" signal "VCC1")
		(22 "In10.Cu" signal "GND4")
		(24 "In11.Cu" signal "IN4")
		(26 "In12.Cu" signal "GND5")
		(28 "In13.Cu" signal "IN5")
		(30 "In14.Cu" signal "GND6")
		(32 "In15.Cu" signal "IN6")
		(34 "In16.Cu" signal "GND7")
		(2 "B.Cu" signal "BOTTOM")
		(9 "F.Adhes" user "F.Adhesive")
		(11 "B.Adhes" user "B.Adhesive")
		(13 "F.Paste" user "Package Geometry/Pastemask Top")
		(15 "B.Paste" user "Package Geometry/Pastemask Bottom")
		(5 "F.SilkS" user "Ref Des/Silkscreen Top")
		(7 "B.SilkS" user "Ref Des/Silkscreen Bottom")
		(1 "F.Mask" user "Board Geometry/Soldermask Top")
		(3 "B.Mask" user "Board Geometry/Soldermask Bottom")
		(17 "Dwgs.User" user "User.Drawings")
		(19 "Cmts.User" user "User.Comments")
		(21 "Eco1.User" user "User.Eco1")
		(23 "Eco2.User" user "User.Eco2")
		(25 "Edge.Cuts" user "Board Geometry/Outline")
		(27 "Margin" user)
		(31 "F.CrtYd" user "Package Geometry/Place Bound Top")
		(29 "B.CrtYd" user "Package Geometry/Place Bound Bottom")
		(35 "F.Fab" user "Ref Des/Assembly Top")
		(33 "B.Fab" user "Ref Des/Assembly Bottom")
	)
	(footprint ""
		(layer "B.Cu")
		(at 119.95912 -244.82044 -90)
		(property "Reference" "C349"
			(at 0 0 90)
			(layer "B.SilkS")
			(hide yes)
			(effects
				(font
					(size 1.27 1.27)
				)
				(justify mirror)
			)
		)
		(property "Value" ""
			(at 0 0 90)
			(layer "B.Fab")
			(effects
				(font
					(size 1.27 1.27)
				)
				(justify mirror)
			)
		)
		(duplicate_pad_numbers_are_jumpers no)
		(fp_line
			(start -1.524 0.762)
			(end 1.524 0.762)
			(stroke
				(width 0.1524)
				(type default)
			)
			(layer "B.SilkS")
		)
		(fp_line
			(start 1.524 0.762)
			(end 1.524 -0.762)
			(stroke
				(width 0.1524)
				(type default)
			)
			(layer "B.SilkS")
		)
		(fp_line
			(start -1.524 -0.762)
			(end -1.524 0.762)
			(stroke
				(width 0.1524)
				(type default)
			)
			(layer "B.SilkS")
		)
		(fp_line
			(start 1.524 -0.762)
			(end -1.524 -0.762)
			(stroke
				(width 0.1524)
				(type default)
			)
			(layer "B.SilkS")
		)
		(fp_line
			(start -1.1049 0.724916)
			(end -1.1049 -0.724916)
			(stroke
				(width 0.1)
				(type default)
			)
			(layer "B.Fab")
		)
		(fp_line
			(start 1.1049 0.724916)
			(end -1.1049 0.724916)
			(stroke
				(width 0.1)
				(type default)
			)
			(layer "B.Fab")
		)
		(fp_line
			(start -1.1049 -0.724916)
			(end 1.1049 -0.724916)
			(stroke
				(width 0.1)
				(type default)
			)
			(layer "B.Fab")
		)
		(fp_line
			(start 1.1049 -0.724916)
			(end 1.1049 0.724916)
			(stroke
				(width 0.1)
				(type default)
			)
			(layer "B.Fab")
		)
		(pad "1" smd rect
			(at 0.889 0 270)
			(size 1.016 1.27)
			(layers "B.Cu" "B.Mask" "B.Paste")
			(net "PVCCIN_CPU1")
		)
		(pad "2" smd rect
			(at -0.889 0 270)
			(size 1.016 1.27)
			(layers "B.Cu" "B.Mask" "B.Paste")
			(net "GND")
		)
	)
	(footprint ""
		(layer "B.Cu")
		(at 122.992134 -324.792086 -90)
		(property "Reference" "PC543_P1_4"
			(at 0 0 90)
			(layer "B.SilkS")
			(hide yes)
			(effects
				(font
					(size 1.27 1.27)
				)
				(justify mirror)
			)
		)
		(property "Value" ""
			(at 0 0 90)
			(layer "B.Fab")
			(effects
				(font
					(size 1.27 1.27)
				)
				(justify mirror)
			)
		)
		(duplicate_pad_numbers_are_jumpers no)
		(fp_line
			(start -1.524 0.762)
			(end 1.524 0.762)
			(stroke
				(width 0.1524)
				(type default)
			)
			(layer "B.SilkS")
		)
		(fp_line
			(start 1.524 0.762)
			(end 1.524 -0.762)
			(stroke
				(width 0.1524)
				(type default)
			)
			(layer "B.SilkS")
		)
		(fp_line
			(start -1.524 -0.762)
			(end -1.524 0.762)
			(stroke
				(width 0.1524)
				(type default)
			)
			(layer "B.SilkS")
		)
		(fp_line
			(start 1.524 -0.762)
			(end -1.524 -0.762)
			(stroke
				(width 0.1524)
				(type default)
			)
			(layer "B.SilkS")
		)
		(fp_line
			(start -1.1049 0.724916)
			(end -1.1049 -0.724916)
			(stroke
				(width 0.1)
				(type default)
			)
			(layer "B.Fab")
		)
		(fp_line
			(start 1.1049 0.724916)
			(end -1.1049 0.724916)
			(stroke
				(width 0.1)
				(type default)
			)
			(layer "B.Fab")
		)
		(fp_line
			(start -1.1049 -0.724916)
			(end 1.1049 -0.724916)
			(stroke
				(width 0.1)
				(type default)
			)
			(layer "B.Fab")
		)
		(fp_line
			(start 1.1049 -0.724916)
			(end 1.1049 0.724916)
			(stroke
				(width 0.1)
				(type default)
			)
			(layer "B.Fab")
		)
		(pad "1" smd rect
			(at 0.889 0 270)
			(size 1.016 1.27)
			(layers "B.Cu" "B.Mask" "B.Paste")
			(net "PVCCIN_CPU1")
		)
		(pad "2" smd rect
			(at -0.889 0 270)
			(size 1.016 1.27)
			(layers "B.Cu" "B.Mask" "B.Paste")
			(net "GND")
		)
	)
	(footprint ""
		(layer "B.Cu")
		(at 250.65482 5.461)
		(property "Reference" "J86"
			(at 4.20751 1.143 270)
			(unlocked yes)
			(layer "B.SilkS")
			(effects
				(font
					(size 0.7874 0.5842)
					(thickness 0.1524)
				)
				(justify left mirror)
			)
		)
		(property "Value" ""
			(at 0 0 0)
			(layer "B.Fab")
			(effects
				(font
					(size 1.27 1.27)
				)
				(justify mirror)
			)
		)
		(duplicate_pad_numbers_are_jumpers no)
		(fp_line
			(start -1.2192 -2.1082)
			(end -1.2192 2.1082)
			(stroke
				(width 0.1524)
				(type default)
			)
			(layer "B.SilkS")
		)
		(fp_line
			(start -1.2192 2.1082)
			(end 1.2192 2.1082)
			(stroke
				(width 0.1524)
				(type default)
			)
			(layer "B.SilkS")
		)
		(fp_line
			(start 1.2192 -2.1082)
			(end -1.2192 -2.1082)
			(stroke
				(width 0.1524)
				(type default)
			)
			(layer "B.SilkS")
		)
		(fp_line
			(start 1.2192 2.1082)
			(end 1.2192 -2.1082)
			(stroke
				(width 0.1524)
				(type default)
			)
			(layer "B.SilkS")
		)
		(pad "" np_thru_hole circle
			(at -3.4671 -1.27 270)
			(size 1.0414 1.0414)
			(drill 1.0414)
			(layers "*.Cu" "*.Mask")
			(clearance 0.381)
			(thermal_gap 0.381)
		)
		(pad "" np_thru_hole circle
			(at -3.4671 1.27 270)
			(size 1.0414 1.0414)
			(drill 1.0414)
			(layers "*.Cu" "*.Mask")
			(clearance 0.381)
			(thermal_gap 0.381)
		)
		(pad "" np_thru_hole circle
			(at 2.8829 -1.27 270)
			(size 1.0414 1.0414)
			(drill 1.0414)
			(layers "*.Cu" "*.Mask")
			(clearance 0.381)
			(thermal_gap 0.381)
		)
		(pad "" np_thru_hole circle
			(at 2.8829 1.27 270)
			(size 1.0414 1.0414)
			(drill 1.0414)
			(layers "*.Cu" "*.Mask")
			(clearance 0.381)
			(thermal_gap 0.381)
		)
		(pad "1" smd rect
			(at -0.8255 -0.249936 270)
			(size 0.3048 0.508)
			(layers "B.Cu" "B.Mask" "B.Paste")
			(net "DELTA_L_85_10INCH_IN4_DN")
		)
		(pad "2" smd rect
			(at -0.8255 0.249936 270)
			(size 0.3048 0.508)
			(layers "B.Cu" "B.Mask" "B.Paste")
			(net "DELTA_L_85_10INCH_IN4_DP")
		)
		(pad "3" smd circle
			(at 0 0 180)
			(size 0 0)
			(layers "B.Cu" "B.Mask" "B.Paste")
			(net "DELTA_L_GND_1")
		)
		(zone
			(layers "F.Cu" "B.Cu" "In1.Cu" "In2.Cu" "In3.Cu" "In4.Cu" "In5.Cu" "In6.Cu"
				"In7.Cu" "In8.Cu" "In9.Cu" "In10.Cu" "In11.Cu" "In12.Cu" "In13.Cu" "In14.Cu"
				"In15.Cu" "In16.Cu"
			)
			(hatch none 0.5)
			(connect_pads
				(clearance 0)
			)
			(min_thickness 0.25)
			(keepout
				(tracks not_allowed)
				(vias allowed)
				(pads allowed)
				(copperpour not_allowed)
				(footprints allowed)
			)
			(placement
				(enabled no)
				(sheetname "")
			)
			(fill
				(thermal_gap 0.5)
				(thermal_bridge_width 0.5)
				(island_removal_mode 0)
			)
			(polygon
				(pts
					(arc
						(start 248.11482 4.191)
						(mid 246.26062 4.191)
						(end 248.11482 4.191)
					)
				)
			)
		)
		(zone
			(layers "F.Cu" "B.Cu" "In1.Cu" "In2.Cu" "In3.Cu" "In4.Cu" "In5.Cu" "In6.Cu"
				"In7.Cu" "In8.Cu" "In9.Cu" "In10.Cu" "In11.Cu" "In12.Cu" "In13.Cu" "In14.Cu"
				"In15.Cu" "In16.Cu"
			)
			(hatch none 0.5)
			(connect_pads
				(clearance 0)
			)
			(min_thickness 0.25)
			(keepout
				(tracks not_allowed)
				(vias allowed)
				(pads allowed)
				(copperpour not_allowed)
				(footprints allowed)
			)
			(placement
				(enabled no)
				(sheetname "")
			)
			(fill
				(thermal_gap 0.5)
				(thermal_bridge_width 0.5)
				(island_removal_mode 0)
			)
			(polygon
				(pts
					(arc
						(start 248.11482 6.731)
						(mid 246.26062 6.731)
						(end 248.11482 6.731)
					)
				)
			)
		)
		(zone
			(layers "F.Cu" "B.Cu" "In1.Cu" "In2.Cu" "In3.Cu" "In4.Cu" "In5.Cu" "In6.Cu"
				"In7.Cu" "In8.Cu" "In9.Cu" "In10.Cu" "In11.Cu" "In12.Cu" "In13.Cu" "In14.Cu"
				"In15.Cu" "In16.Cu"
			)
			(hatch none 0.5)
			(connect_pads
				(clearance 0)
			)
			(min_thickness 0.25)
			(keepout
				(tracks not_allowed)
				(vias allowed)
				(pads allowed)
				(copperpour not_allowed)
				(footprints allowed)
			)
			(placement
				(enabled no)
				(sheetname "")
			)
			(fill
				(thermal_gap 0.5)
				(thermal_bridge_width 0.5)
				(island_removal_mode 0)
			)
			(polygon
				(pts
					(arc
						(start 254.46482 4.191)
						(mid 252.61062 4.191)
						(end 254.46482 4.191)
					)
				)
			)
		)
		(zone
			(layers "F.Cu" "B.Cu" "In1.Cu" "In2.Cu" "In3.Cu" "In4.Cu" "In5.Cu" "In6.Cu"
				"In7.Cu" "In8.Cu" "In9.Cu" "In10.Cu" "In11.Cu" "In12.Cu" "In13.Cu" "In14.Cu"
				"In15.Cu" "In16.Cu"
			)
			(hatch none 0.5)
			(connect_pads
				(clearance 0)
			)
			(min_thickness 0.25)
			(keepout
				(tracks not_allowed)
				(vias allowed)
				(pads allowed)
				(copperpour not_allowed)
				(footprints allowed)
			)
			(placement
				(enabled no)
				(sheetname "")
			)
			(fill
				(thermal_gap 0.5)
				(thermal_bridge_width 0.5)
				(island_removal_mode 0)
			)
			(polygon
				(pts
					(arc
						(start 254.46482 6.731)
						(mid 252.61062 6.731)
						(end 254.46482 6.731)
					)
				)
			)
		)
		(zone
			(layer "B.Cu")
			(hatch none 0.5)
			(connect_pads
				(clearance 0)
			)
			(min_thickness 0.25)
			(keepout
				(tracks not_allowed)
				(vias allowed)
				(pads allowed)
				(copperpour not_allowed)
				(footprints allowed)
			)
			(placement
				(enabled no)
				(sheetname "")
			)
			(fill
				(thermal_gap 0.5)
				(thermal_bridge_width 0.5)
				(island_removal_mode 0)
			)
			(polygon
				(pts
					(xy 249.53722 4.91236) (xy 249.53722 5.007864) (xy 250.13412 5.007864) (xy 250.13412 5.414264)
					(xy 249.53722 5.414264) (xy 249.53722 5.507736) (xy 250.13412 5.507736) (xy 250.13412 5.914136)
					(xy 249.53722 5.914136) (xy 249.53722 6.00964) (xy 250.23572 6.00964) (xy 250.23572 4.91236)
				)
			)
		)
	)
	(footprint ""
		(layer "B.Cu")
		(at 12.217146 -319.268856 180)
		(property "Reference" "R899"
			(at 0 0 0)
			(layer "B.SilkS")
			(hide yes)
			(effects
				(font
					(size 1.27 1.27)
				)
				(justify mirror)
			)
		)
		(property "Value" ""
			(at 0 0 0)
			(layer "B.Fab")
			(effects
				(font
					(size 1.27 1.27)
				)
				(justify mirror)
			)
		)
		(duplicate_pad_numbers_are_jumpers no)
		(fp_line
			(start 0.7874 0.4064)
			(end 0.7874 -0.4064)
			(stroke
				(width 0.1524)
				(type default)
			)
			(layer "B.SilkS")
		)
		(fp_line
			(start 0.7874 -0.4064)
			(end -0.7874 -0.4064)
			(stroke
				(width 0.1524)
				(type default)
			)
			(layer "B.SilkS")
		)
		(fp_line
			(start -0.7874 0.4064)
			(end 0.7874 0.4064)
			(stroke
				(width 0.1524)
				(type default)
			)
			(layer "B.SilkS")
		)
		(fp_line
			(start -0.7874 -0.4064)
			(end -0.7874 0.4064)
			(stroke
				(width 0.1524)
				(type default)
			)
			(layer "B.SilkS")
		)
		(fp_line
			(start 0.67945 0.3048)
			(end 0.67945 -0.305054)
			(stroke
				(width 0.1)
				(type default)
			)
			(layer "B.Fab")
		)
		(fp_line
			(start 0.67945 -0.305054)
			(end 0.12065 -0.305054)
			(stroke
				(width 0.1)
				(type default)
			)
			(layer "B.Fab")
		)
		(fp_line
			(start 0.12065 0.3048)
			(end 0.67945 0.3048)
			(stroke
				(width 0.1)
				(type default)
			)
			(layer "B.Fab")
		)
		(fp_line
			(start 0.12065 0.2794)
			(end 0.12065 0.3048)
			(stroke
				(width 0.1)
				(type default)
			)
			(layer "B.Fab")
		)
		(fp_line
			(start 0.12065 -0.2794)
			(end -0.12065 -0.2794)
			(stroke
				(width 0.1)
				(type default)
			)
			(layer "B.Fab")
		)
		(fp_line
			(start 0.12065 -0.305054)
			(end 0.12065 -0.2794)
			(stroke
				(width 0.1)
				(type default)
			)
			(layer "B.Fab")
		)
		(fp_line
			(start -0.120396 0.3048)
			(end -0.120396 0.2794)
			(stroke
				(width 0.1)
				(type default)
			)
			(layer "B.Fab")
		)
		(fp_line
			(start -0.120396 0.2794)
			(end 0.12065 0.2794)
			(stroke
				(width 0.1)
				(type default)
			)
			(layer "B.Fab")
		)
		(fp_line
			(start -0.12065 -0.2794)
			(end -0.12065 -0.3048)
			(stroke
				(width 0.1)
				(type default)
			)
			(layer "B.Fab")
		)
		(fp_line
			(start -0.12065 -0.3048)
			(end -0.67945 -0.3048)
			(stroke
				(width 0.1)
				(type default)
			)
			(layer "B.Fab")
		)
		(fp_line
			(start -0.67945 0.3048)
			(end -0.120396 0.3048)
			(stroke
				(width 0.1)
				(type default)
			)
			(layer "B.Fab")
		)
		(fp_line
			(start -0.67945 -0.3048)
			(end -0.67945 0.3048)
			(stroke
				(width 0.1)
				(type default)
			)
			(layer "B.Fab")
		)
		(pad "1" smd circle
			(at 0.40005 0)
			(size 0 0)
			(layers "B.Cu" "B.Mask" "B.Paste")
			(net "PWRGD_CHD_CPU1_DIMM1")
		)
		(pad "2" smd circle
			(at -0.40005 0)
			(size 0 0)
			(layers "B.Cu" "B.Mask" "B.Paste")
			(net "PWRGD_FAIL_CPU1_CD")
		)
	)
	(footprint ""
		(layer "B.Cu")
		(at 135.489442 -343.927938 -90)
		(property "Reference" "PR287"
			(at 0 0 90)
			(layer "B.SilkS")
			(hide yes)
			(effects
				(font
					(size 1.27 1.27)
				)
				(justify mirror)
			)
		)
		(property "Value" ""
			(at 0 0 90)
			(layer "B.Fab")
			(effects
				(font
					(size 1.27 1.27)
				)
				(justify mirror)
			)
		)
		(duplicate_pad_numbers_are_jumpers no)
		(fp_line
			(start -0.7874 0.4064)
			(end 0.7874 0.4064)
			(stroke
				(width 0.1524)
				(type default)
			)
			(layer "B.SilkS")
		)
		(fp_line
			(start 0.7874 0.4064)
			(end 0.7874 -0.4064)
			(stroke
				(width 0.1524)
				(type default)
			)
			(layer "B.SilkS")
		)
		(fp_line
			(start -0.7874 -0.4064)
			(end -0.7874 0.4064)
			(stroke
				(width 0.1524)
				(type default)
			)
			(layer "B.SilkS")
		)
		(fp_line
			(start 0.7874 -0.4064)
			(end -0.7874 -0.4064)
			(stroke
				(width 0.1524)
				(type default)
			)
			(layer "B.SilkS")
		)
		(fp_line
			(start -0.67945 0.3048)
			(end -0.120396 0.3048)
			(stroke
				(width 0.1)
				(type default)
			)
			(layer "B.Fab")
		)
		(fp_line
			(start -0.120396 0.3048)
			(end -0.120396 0.2794)
			(stroke
				(width 0.1)
				(type default)
			)
			(layer "B.Fab")
		)
		(fp_line
			(start 0.12065 0.3048)
			(end 0.67945 0.3048)
			(stroke
				(width 0.1)
				(type default)
			)
			(layer "B.Fab")
		)
		(fp_line
			(start 0.67945 0.3048)
			(end 0.67945 -0.305054)
			(stroke
				(width 0.1)
				(type default)
			)
			(layer "B.Fab")
		)
		(fp_line
			(start -0.120396 0.2794)
			(end 0.12065 0.2794)
			(stroke
				(width 0.1)
				(type default)
			)
			(layer "B.Fab")
		)
		(fp_line
			(start 0.12065 0.2794)
			(end 0.12065 0.3048)
			(stroke
				(width 0.1)
				(type default)
			)
			(layer "B.Fab")
		)
		(fp_line
			(start -0.12065 -0.2794)
			(end -0.12065 -0.3048)
			(stroke
				(width 0.1)
				(type default)
			)
			(layer "B.Fab")
		)
		(fp_line
			(start 0.12065 -0.2794)
			(end -0.12065 -0.2794)
			(stroke
				(width 0.1)
				(type default)
			)
			(layer "B.Fab")
		)
		(fp_line
			(start -0.67945 -0.3048)
			(end -0.67945 0.3048)
			(stroke
				(width 0.1)
				(type default)
			)
			(layer "B.Fab")
		)
		(fp_line
			(start -0.12065 -0.3048)
			(end -0.67945 -0.3048)
			(stroke
				(width 0.1)
				(type default)
			)
			(layer "B.Fab")
		)
		(fp_line
			(start 0.12065 -0.305054)
			(end 0.12065 -0.2794)
			(stroke
				(width 0.1)
				(type default)
			)
			(layer "B.Fab")
		)
		(fp_line
			(start 0.67945 -0.305054)
			(end 0.12065 -0.305054)
			(stroke
				(width 0.1)
				(type default)
			)
			(layer "B.Fab")
		)
		(pad "1" smd circle
			(at 0.40005 0 90)
			(size 0 0)
			(layers "B.Cu" "B.Mask" "B.Paste")
			(net "PVCCIN_CPU1_PVCC")
		)
		(pad "2" smd circle
			(at -0.40005 0 90)
			(size 0 0)
			(layers "B.Cu" "B.Mask" "B.Paste")
			(net "PVCCIN_CPU1_VDD8")
		)
	)
	(footprint ""
		(layer "B.Cu")
		(at 188.981588 -316.866778 90)
		(property "Reference" "R3904"
			(at 0 0 90)
			(layer "B.SilkS")
			(hide yes)
			(effects
				(font
					(size 1.27 1.27)
				)
				(justify mirror)
			)
		)
		(property "Value" ""
			(at 0 0 90)
			(layer "B.Fab")
			(effects
				(font
					(size 1.27 1.27)
				)
				(justify mirror)
			)
		)
		(duplicate_pad_numbers_are_jumpers no)
		(fp_line
			(start 0.7874 -0.4064)
			(end -0.7874 -0.4064)
			(stroke
				(width 0.1524)
				(type default)
			)
			(layer "B.SilkS")
		)
		(fp_line
			(start -0.7874 -0.4064)
			(end -0.7874 0.4064)
			(stroke
				(width 0.1524)
				(type default)
			)
			(layer "B.SilkS")
		)
		(fp_line
			(start 0.7874 0.4064)
			(end 0.7874 -0.4064)
			(stroke
				(width 0.1524)
				(type default)
			)
			(layer "B.SilkS")
		)
		(fp_line
			(start -0.7874 0.4064)
			(end 0.7874 0.4064)
			(stroke
				(width 0.1524)
				(type default)
			)
			(layer "B.SilkS")
		)
		(fp_line
			(start 0.67945 -0.305054)
			(end 0.12065 -0.305054)
			(stroke
				(width 0.1)
				(type default)
			)
			(layer "B.Fab")
		)
		(fp_line
			(start 0.12065 -0.305054)
			(end 0.12065 -0.2794)
			(stroke
				(width 0.1)
				(type default)
			)
			(layer "B.Fab")
		)
		(fp_line
			(start -0.12065 -0.3048)
			(end -0.67945 -0.3048)
			(stroke
				(width 0.1)
				(type default)
			)
			(layer "B.Fab")
		)
		(fp_line
			(start -0.67945 -0.3048)
			(end -0.67945 0.3048)
			(stroke
				(width 0.1)
				(type default)
			)
			(layer "B.Fab")
		)
		(fp_line
			(start 0.12065 -0.2794)
			(end -0.12065 -0.2794)
			(stroke
				(width 0.1)
				(type default)
			)
			(layer "B.Fab")
		)
		(fp_line
			(start -0.12065 -0.2794)
			(end -0.12065 -0.3048)
			(stroke
				(width 0.1)
				(type default)
			)
			(layer "B.Fab")
		)
		(fp_line
			(start 0.12065 0.2794)
			(end 0.12065 0.3048)
			(stroke
				(width 0.1)
				(type default)
			)
			(layer "B.Fab")
		)
		(fp_line
			(start -0.120396 0.2794)
			(end 0.12065 0.2794)
			(stroke
				(width 0.1)
				(type default)
			)
			(layer "B.Fab")
		)
		(fp_line
			(start 0.67945 0.3048)
			(end 0.67945 -0.305054)
			(stroke
				(width 0.1)
				(type default)
			)
			(layer "B.Fab")
		)
		(fp_line
			(start 0.12065 0.3048)
			(end 0.67945 0.3048)
			(stroke
				(width 0.1)
				(type default)
			)
			(layer "B.Fab")
		)
		(fp_line
			(start -0.120396 0.3048)
			(end -0.120396 0.2794)
			(stroke
				(width 0.1)
				(type default)
			)
			(layer "B.Fab")
		)
		(fp_line
			(start -0.67945 0.3048)
			(end -0.120396 0.3048)
			(stroke
				(width 0.1)
				(type default)
			)
			(layer "B.Fab")
		)
		(pad "1" smd circle
			(at 0.40005 0 270)
			(size 0 0)
			(layers "B.Cu" "B.Mask" "B.Paste")
			(net "I3C_SPD_DDREFGH_CPU1_LVC1_SCL_5")
		)
		(pad "2" smd circle
			(at -0.40005 0 270)
			(size 0 0)
			(layers "B.Cu" "B.Mask" "B.Paste")
			(net "I3C_SPD_DDREFGH_CPU1_LVC1_SCL")
		)
	)
)
